(kicad_pcb
	(version 20260206)
	(generator "pcbnew")
	(generator_version "10.0")
	(general
		(thickness 1.6)
		(legacy_teardrops no)
	)
	(paper "A4")
	(title_block
		(title "Bryce Canyon_F.DPB_16315-1-OCP.brd")
		(comment 1 "Bryce Canyon / footprints 2025-2033 of 2223")
	)
	(layers
		(0 "F.Cu" signal "TOP")
		(4 "In1.Cu" signal "L2GND")
		(6 "In2.Cu" signal "L3")
		(8 "In3.Cu" signal "L4GND")
		(10 "In4.Cu" signal "L5")
		(12 "In5.Cu" signal "L6VCC")
		(14 "In6.Cu" signal "L7VCC")
		(16 "In7.Cu" signal "L8")
		(18 "In8.Cu" signal "L9GND")
		(20 "In9.Cu" signal "L10")
		(22 "In10.Cu" signal "L11GND")
		(2 "B.Cu" signal "BOTTOM")
		(9 "F.Adhes" user "F.Adhesive")
		(11 "B.Adhes" user "B.Adhesive")
		(13 "F.Paste" user "Package Geometry/Pastemask Top")
		(15 "B.Paste" user "Package Geometry/Pastemask Bottom")
		(5 "F.SilkS" user "Ref Des/Silkscreen Top")
		(7 "B.SilkS" user "Ref Des/Silkscreen Bottom")
		(1 "F.Mask" user "Board Geometry/Soldermask Top")
		(3 "B.Mask" user "Board Geometry/Soldermask Bottom")
		(17 "Dwgs.User" user "User.Drawings")
		(19 "Cmts.User" user "User.Comments")
		(21 "Eco1.User" user "User.Eco1")
		(23 "Eco2.User" user "User.Eco2")
		(25 "Edge.Cuts" user "Board Geometry/Outline")
		(27 "Margin" user)
		(31 "F.CrtYd" user "Package Geometry/Place Bound Top")
		(29 "B.CrtYd" user "Package Geometry/Place Bound Bottom")
		(35 "F.Fab" user "Ref Des/Assembly Top")
		(33 "B.Fab" user "Ref Des/Assembly Bottom")
	)
	(footprint ""
		(layer "F.Cu")
		(at 15.223998 -47.157894 180)
		(property "Reference" "R698"
			(at 0 0 180)
			(layer "F.SilkS")
			(hide yes)
			(effects
				(font
					(size 1.27 1.27)
				)
			)
		)
		(property "Value" "200KR2F-L-GP"
			(at 0.064008 -3.993896 180)
			(unlocked yes)
			(layer "F.Fab")
			(hide yes)
			(effects
				(font
					(size 1.016 1.016)
					(thickness 0.1524)
				)
			)
		)
		(property "Device Type" "R402H16"
			(at 0.064008 -5.517896 180)
			(unlocked yes)
			(layer "F.Fab")
			(hide yes)
			(effects
				(font
					(size 1.016 1.016)
					(thickness 0.1524)
				)
			)
		)
		(duplicate_pad_numbers_are_jumpers no)
		(fp_line
			(start 0.508 -0.9398)
			(end -0.508 -0.9398)
			(stroke
				(width 0.1524)
				(type default)
			)
			(layer "F.SilkS")
		)
		(fp_line
			(start -0.508 -0.9398)
			(end -0.508 0.9398)
			(stroke
				(width 0.1524)
				(type default)
			)
			(layer "F.SilkS")
		)
		(fp_rect
			(start -0.508 0.9398)
			(end 0.508 -0.9398)
			(stroke
				(width 0)
				(type default)
			)
			(fill no)
			(layer "F.CrtYd")
		)
		(fp_rect
			(start -0.508 0.9398)
			(end 0.508 -0.9398)
			(stroke
				(width 0)
				(type default)
			)
			(fill no)
			(layer "F.Fab")
		)
		(pad "1" smd custom
			(at 0 -0.4445 180)
			(size 0.1397 0.1397)
			(layers "F.Cu" "F.Mask" "F.Paste")
			(net "SW_HDD_R24")
			(options
				(clearance outline)
				(anchor circle)
			)
			(primitives
				(gr_poly
					(pts
						(arc
							(start -0.1778 -0.2794)
							(mid -0.249642 -0.249642)
							(end -0.2794 -0.1778)
						)
						(arc
							(start -0.2794 0.1778)
							(mid -0.249642 0.249642)
							(end -0.1778 0.2794)
						)
						(arc
							(start 0.1778 0.2794)
							(mid 0.249642 0.249642)
							(end 0.2794 0.1778)
						)
						(arc
							(start 0.2794 -0.1778)
							(mid 0.249642 -0.249642)
							(end 0.1778 -0.2794)
						)
					)
					(width 0)
					(fill yes)
				)
			)
		)
		(pad "2" smd custom
			(at 0 0.4445 180)
			(size 0.1397 0.1397)
			(layers "F.Cu" "F.Mask" "F.Paste")
			(net "SW_HDD_N24")
			(options
				(clearance outline)
				(anchor circle)
			)
			(primitives
				(gr_poly
					(pts
						(arc
							(start -0.1778 -0.2794)
							(mid -0.249642 -0.249642)
							(end -0.2794 -0.1778)
						)
						(arc
							(start -0.2794 0.1778)
							(mid -0.249642 0.249642)
							(end -0.1778 0.2794)
						)
						(arc
							(start 0.1778 0.2794)
							(mid 0.249642 0.249642)
							(end 0.2794 0.1778)
						)
						(arc
							(start 0.2794 -0.1778)
							(mid 0.249642 -0.249642)
							(end 0.1778 -0.2794)
						)
					)
					(width 0)
					(fill yes)
				)
			)
		)
	)
	(footprint ""
		(layer "F.Cu")
		(at 270.383 -280.162)
		(property "Reference" "C35"
			(at 0 0 0)
			(layer "F.SilkS")
			(hide yes)
			(effects
				(font
					(size 1.27 1.27)
				)
			)
		)
		(property "Value" "SC1U16V3KX-5GP"
			(at 0 -2.8194 0)
			(unlocked yes)
			(layer "F.Fab")
			(hide yes)
			(effects
				(font
					(size 1.016 1.016)
					(thickness 0.1524)
				)
			)
		)
		(property "Device Type" "C603H36"
			(at 0 -4.3434 0)
			(unlocked yes)
			(layer "F.Fab")
			(hide yes)
			(effects
				(font
					(size 1.016 1.016)
					(thickness 0.1524)
				)
			)
		)
		(duplicate_pad_numbers_are_jumpers no)
		(fp_line
			(start 0.508 0)
			(end -0.508 0)
			(stroke
				(width 0.2032)
				(type default)
			)
			(layer "F.SilkS")
		)
		(fp_rect
			(start -0.5842 1.3335)
			(end 0.5842 -1.3335)
			(stroke
				(width 0)
				(type default)
			)
			(fill no)
			(layer "F.CrtYd")
		)
		(fp_rect
			(start -0.5842 1.3335)
			(end 0.5842 -1.3335)
			(stroke
				(width 0)
				(type default)
			)
			(fill no)
			(layer "F.Fab")
		)
		(pad "1" smd custom
			(at 0 -0.762)
			(size 0.2159 0.2159)
			(layers "F.Cu" "F.Mask" "F.Paste")
			(net "P3V3_STBY_A")
			(options
				(clearance outline)
				(anchor circle)
			)
			(primitives
				(gr_poly
					(pts
						(arc
							(start -0.3302 -0.4318)
							(mid -0.402042 -0.402042)
							(end -0.4318 -0.3302)
						)
						(arc
							(start -0.4318 0.3302)
							(mid -0.402042 0.402042)
							(end -0.3302 0.4318)
						)
						(arc
							(start 0.3302 0.4318)
							(mid 0.402042 0.402042)
							(end 0.4318 0.3302)
						)
						(arc
							(start 0.4318 -0.3302)
							(mid 0.402042 -0.402042)
							(end 0.3302 -0.4318)
						)
					)
					(width 0)
					(fill yes)
				)
			)
		)
		(pad "2" smd custom
			(at 0 0.762)
			(size 0.2159 0.2159)
			(layers "F.Cu" "F.Mask" "F.Paste")
			(net "GND")
			(options
				(clearance outline)
				(anchor circle)
			)
			(primitives
				(gr_poly
					(pts
						(arc
							(start -0.3302 -0.4318)
							(mid -0.402042 -0.402042)
							(end -0.4318 -0.3302)
						)
						(arc
							(start -0.4318 0.3302)
							(mid -0.402042 0.402042)
							(end -0.3302 0.4318)
						)
						(arc
							(start 0.3302 0.4318)
							(mid 0.402042 0.402042)
							(end 0.4318 0.3302)
						)
						(arc
							(start 0.4318 -0.3302)
							(mid 0.402042 -0.402042)
							(end 0.3302 -0.4318)
						)
					)
					(width 0)
					(fill yes)
				)
			)
		)
	)
	(footprint ""
		(layer "F.Cu")
		(at 449.545202 -256.34315 -90)
		(property "Reference" "C637"
			(at 0 0 270)
			(layer "F.SilkS")
			(hide yes)
			(effects
				(font
					(size 1.27 1.27)
				)
			)
		)
		(property "Value" "SC1U16V3KX-5GP"
			(at 0 -2.8194 270)
			(unlocked yes)
			(layer "F.Fab")
			(hide yes)
			(effects
				(font
					(size 1.016 1.016)
					(thickness 0.1524)
				)
			)
		)
		(property "Device Type" "C603H36"
			(at 0 -4.3434 270)
			(unlocked yes)
			(layer "F.Fab")
			(hide yes)
			(effects
				(font
					(size 1.016 1.016)
					(thickness 0.1524)
				)
			)
		)
		(duplicate_pad_numbers_are_jumpers no)
		(fp_line
			(start 0.508 0)
			(end -0.508 0)
			(stroke
				(width 0.2032)
				(type default)
			)
			(layer "F.SilkS")
		)
		(fp_rect
			(start -0.5842 1.3335)
			(end 0.5842 -1.3335)
			(stroke
				(width 0)
				(type default)
			)
			(fill no)
			(layer "F.CrtYd")
		)
		(fp_rect
			(start -0.5842 1.3335)
			(end 0.5842 -1.3335)
			(stroke
				(width 0)
				(type default)
			)
			(fill no)
			(layer "F.Fab")
		)
		(pad "1" smd custom
			(at 0 -0.762 270)
			(size 0.2159 0.2159)
			(layers "F.Cu" "F.Mask" "F.Paste")
			(net "P5V_C_EN_R")
			(options
				(clearance outline)
				(anchor circle)
			)
			(primitives
				(gr_poly
					(pts
						(arc
							(start -0.3302 -0.4318)
							(mid -0.402042 -0.402042)
							(end -0.4318 -0.3302)
						)
						(arc
							(start -0.4318 0.3302)
							(mid -0.402042 0.402042)
							(end -0.3302 0.4318)
						)
						(arc
							(start 0.3302 0.4318)
							(mid 0.402042 0.402042)
							(end 0.4318 0.3302)
						)
						(arc
							(start 0.4318 -0.3302)
							(mid 0.402042 -0.402042)
							(end 0.3302 -0.4318)
						)
					)
					(width 0)
					(fill yes)
				)
			)
		)
		(pad "2" smd custom
			(at 0 0.762 270)
			(size 0.2159 0.2159)
			(layers "F.Cu" "F.Mask" "F.Paste")
			(net "GND")
			(options
				(clearance outline)
				(anchor circle)
			)
			(primitives
				(gr_poly
					(pts
						(arc
							(start -0.3302 -0.4318)
							(mid -0.402042 -0.402042)
							(end -0.4318 -0.3302)
						)
						(arc
							(start -0.4318 0.3302)
							(mid -0.402042 0.402042)
							(end -0.3302 0.4318)
						)
						(arc
							(start 0.3302 0.4318)
							(mid 0.402042 0.402042)
							(end 0.4318 0.3302)
						)
						(arc
							(start 0.4318 -0.3302)
							(mid 0.402042 -0.402042)
							(end 0.3302 -0.4318)
						)
					)
					(width 0)
					(fill yes)
				)
			)
		)
	)
	(footprint ""
		(layer "F.Cu")
		(at 224.536 -127.8382 -90)
		(property "Reference" "TP203"
			(at 0 0 270)
			(layer "F.SilkS")
			(hide yes)
			(effects
				(font
					(size 1.27 1.27)
				)
			)
		)
		(property "Value" "TPAD32-GP"
			(at -0.0508 -1.6764 270)
			(unlocked yes)
			(layer "F.Fab")
			(hide yes)
			(effects
				(font
					(size 1.016 1.016)
					(thickness 0.1524)
				)
			)
		)
		(property "Device Type" "TPAD32"
			(at -0.0508 -3.2004 270)
			(unlocked yes)
			(layer "F.Fab")
			(hide yes)
			(effects
				(font
					(size 1.016 1.016)
					(thickness 0.1524)
				)
			)
		)
		(duplicate_pad_numbers_are_jumpers no)
		(fp_poly
			(pts
				(arc
					(start 0 -0.4064)
					(mid 0 0.4064)
					(end 0 -0.4064)
				)
			)
			(stroke
				(width 0)
				(type default)
			)
			(fill no)
			(layer "F.CrtYd")
		)
		(fp_poly
			(pts
				(arc
					(start 0 -0.7112)
					(mid 0 0.7112)
					(end 0 -0.7112)
				)
			)
			(stroke
				(width 0)
				(type default)
			)
			(fill no)
			(layer "F.Fab")
		)
		(pad "1" smd circle
			(at 0 0 270)
			(size 0.8128 0.8128)
			(layers "F.Cu" "F.Mask" "F.Paste")
			(net "TP_COMP_A_SATA_P0_TX_DP")
		)
	)
	(footprint ""
		(layer "F.Cu")
		(at 456.674982 -92.799916)
		(property "Reference" ""
			(at 0 0 0)
			(layer "F.SilkS")
			(hide yes)
			(effects
				(font
					(size 1.27 1.27)
				)
			)
		)
		(property "Value" "*"
			(at -8.398764 -8.057642 0)
			(unlocked yes)
			(layer "F.Fab")
			(hide yes)
			(effects
				(font
					(size 1.016 1.016)
					(thickness 0.1524)
				)
			)
		)
		(duplicate_pad_numbers_are_jumpers no)
		(fp_poly
			(pts
				(arc
					(start 7.3152 0)
					(mid 0 7.3152)
					(end -7.3152 0)
				)
				(arc
					(start -7.3152 -5.9944)
					(mid 0 -13.3096)
					(end 7.3152 -5.9944)
				)
			)
			(stroke
				(width 0)
				(type default)
			)
			(fill no)
			(layer "B.CrtYd")
		)
		(fp_poly
			(pts
				(arc
					(start 7.3152 0)
					(mid 0 7.3152)
					(end -7.3152 0)
				)
				(arc
					(start -7.3152 -5.9944)
					(mid 0 -13.3096)
					(end 7.3152 -5.9944)
				)
			)
			(stroke
				(width 0)
				(type default)
			)
			(fill no)
			(layer "F.CrtYd")
		)
		(fp_poly
			(pts
				(arc
					(start 7.3152 0)
					(mid 0 7.3152)
					(end -7.3152 0)
				)
				(arc
					(start -7.3152 -5.9944)
					(mid 0 -13.3096)
					(end 7.3152 -5.9944)
				)
			)
			(stroke
				(width 0)
				(type default)
			)
			(fill no)
			(layer "B.Fab")
		)
		(fp_poly
			(pts
				(arc
					(start 7.3152 0)
					(mid 0 7.3152)
					(end -7.3152 0)
				)
				(arc
					(start -7.3152 -5.9944)
					(mid 0 -13.3096)
					(end 7.3152 -5.9944)
				)
			)
			(stroke
				(width 0)
				(type default)
			)
			(fill no)
			(layer "F.Fab")
		)
		(pad "1" thru_hole oval
			(at 0 0)
			(size 14.0208 20.0152)
			(drill 0.0254
				(offset 0 -2.9972)
			)
			(layers "*.Cu" "*.Mask")
			(remove_unused_layers no)
			(net "Net_37")
			(clearance -1.002284)
			(thermal_gap 0.1524)
			(padstack
				(mode front_inner_back)
				(layer "Inner"
					(shape custom)
					(size 2.928012 2.928012)
					(options
						(anchor circle)
					)
					(primitives
						(gr_poly
							(pts
								(arc
									(start 4.571746 -2.084324)
									(mid 0.000333 7.430372)
									(end -4.571492 -2.084324)
								)
								(arc
									(start -4.571492 -2.084324)
									(mid -3.570296 -3.611977)
									(end -2.875026 -5.30098)
								)
								(arc
									(start -2.875026 -5.30098)
									(mid 0.000217 -7.43089)
									(end 2.87528 -5.30098)
								)
								(arc
									(start 2.87528 -5.30098)
									(mid 3.570511 -3.611956)
									(end 4.571746 -2.084324)
								)
							)
							(width 0)
							(fill yes)
						)
					)
					(clearance 0.1524)
				)
				(layer "B.Cu"
					(shape oval)
					(size 14.0208 20.0152)
					(offset 0 -2.9972)
					(clearance -1.002284)
				)
			)
		)
		(zone
			(layers "F.Cu" "B.Cu" "In1.Cu" "In2.Cu" "In3.Cu" "In4.Cu" "In5.Cu" "In6.Cu"
				"In7.Cu" "In8.Cu" "In9.Cu" "In10.Cu"
			)
			(hatch none 0.5)
			(connect_pads
				(clearance 0)
			)
			(min_thickness 0.25)
			(keepout
				(tracks not_allowed)
				(vias allowed)
				(pads allowed)
				(copperpour not_allowed)
				(footprints allowed)
			)
			(placement
				(enabled no)
				(sheetname "")
			)
			(fill
				(thermal_gap 0.5)
				(thermal_bridge_width 0.5)
				(island_removal_mode 0)
			)
			(polygon
				(pts
					(arc
						(start 449.664582 -98.794316)
						(mid 456.674982 -105.804716)
						(end 463.685382 -98.794316)
					)
					(arc
						(start 463.685382 -92.799916)
						(mid 456.674982 -85.789516)
						(end 449.664582 -92.799916)
					)
				)
			)
		)
	)
	(footprint ""
		(layer "F.Cu")
		(at 98.6028 -298.704)
		(property "Reference" "TP12"
			(at 0 0 0)
			(layer "F.SilkS")
			(hide yes)
			(effects
				(font
					(size 1.27 1.27)
				)
			)
		)
		(property "Value" "TPAD32-GP"
			(at -0.0508 -1.6764 0)
			(unlocked yes)
			(layer "F.Fab")
			(hide yes)
			(effects
				(font
					(size 1.016 1.016)
					(thickness 0.1524)
				)
			)
		)
		(property "Device Type" "TPAD32"
			(at -0.0508 -3.2004 0)
			(unlocked yes)
			(layer "F.Fab")
			(hide yes)
			(effects
				(font
					(size 1.016 1.016)
					(thickness 0.1524)
				)
			)
		)
		(duplicate_pad_numbers_are_jumpers no)
		(fp_poly
			(pts
				(arc
					(start 0.4064 0)
					(mid -0.4064 0)
					(end 0.4064 0)
				)
			)
			(stroke
				(width 0)
				(type default)
			)
			(fill no)
			(layer "F.CrtYd")
		)
		(fp_poly
			(pts
				(arc
					(start 0.7112 0)
					(mid -0.7112 0)
					(end 0.7112 0)
				)
			)
			(stroke
				(width 0)
				(type default)
			)
			(fill no)
			(layer "F.Fab")
		)
		(pad "1" smd circle
			(at 0 0)
			(size 0.8128 0.8128)
			(layers "F.Cu" "F.Mask" "F.Paste")
			(net "ACT_HDD_2")
		)
	)
	(footprint ""
		(layer "F.Cu")
		(at 349.812102 -176.127918 -90)
		(property "Reference" "C293"
			(at 0 0 270)
			(layer "F.SilkS")
			(hide yes)
			(effects
				(font
					(size 1.27 1.27)
				)
			)
		)
		(property "Value" "SCD01U50V2KX-1GP"
			(at 1.1811 -2.7051 270)
			(unlocked yes)
			(layer "F.Fab")
			(hide yes)
			(effects
				(font
					(size 1.016 1.016)
					(thickness 0.1524)
				)
			)
		)
		(property "Device Type" "C402H22"
			(at 1.1811 -4.2291 270)
			(unlocked yes)
			(layer "F.Fab")
			(hide yes)
			(effects
				(font
					(size 1.016 1.016)
					(thickness 0.1524)
				)
			)
		)
		(duplicate_pad_numbers_are_jumpers no)
		(fp_rect
			(start -0.4318 0.9525)
			(end 0.4318 -0.9525)
			(stroke
				(width 0)
				(type default)
			)
			(fill no)
			(layer "F.CrtYd")
		)
		(fp_rect
			(start -0.4318 0.9525)
			(end 0.4318 -0.9525)
			(stroke
				(width 0)
				(type default)
			)
			(fill no)
			(layer "F.Fab")
		)
		(pad "1" smd custom
			(at 0 -0.4445 270)
			(size 0.1524 0.1524)
			(layers "F.Cu" "F.Mask" "F.Paste")
			(net "HDD_PRSNT_19")
			(options
				(clearance outline)
				(anchor circle)
			)
			(primitives
				(gr_poly
					(pts
						(arc
							(start 0.3048 -0.2032)
							(mid 0.275042 -0.275042)
							(end 0.2032 -0.3048)
						)
						(arc
							(start -0.2032 -0.3048)
							(mid -0.275042 -0.275042)
							(end -0.3048 -0.2032)
						)
						(arc
							(start -0.3048 0.2032)
							(mid -0.275042 0.275042)
							(end -0.2032 0.3048)
						)
						(arc
							(start 0.2032 0.3048)
							(mid 0.275042 0.275042)
							(end 0.3048 0.2032)
						)
					)
					(width 0)
					(fill yes)
				)
			)
		)
		(pad "2" smd custom
			(at 0 0.4445 270)
			(size 0.1524 0.1524)
			(layers "F.Cu" "F.Mask" "F.Paste")
			(net "GND")
			(options
				(clearance outline)
				(anchor circle)
			)
			(primitives
				(gr_poly
					(pts
						(arc
							(start 0.3048 -0.2032)
							(mid 0.275042 -0.275042)
							(end 0.2032 -0.3048)
						)
						(arc
							(start -0.2032 -0.3048)
							(mid -0.275042 -0.275042)
							(end -0.3048 -0.2032)
						)
						(arc
							(start -0.3048 0.2032)
							(mid -0.275042 0.275042)
							(end -0.2032 0.3048)
						)
						(arc
							(start 0.2032 0.3048)
							(mid 0.275042 0.275042)
							(end 0.3048 0.2032)
						)
					)
					(width 0)
					(fill yes)
				)
			)
		)
	)
	(footprint ""
		(layer "F.Cu")
		(at 98.643948 -68.747894)
		(property "Reference" "TP132"
			(at 0 0 0)
			(layer "F.SilkS")
			(hide yes)
			(effects
				(font
					(size 1.27 1.27)
				)
			)
		)
		(property "Value" "TPAD32-GP"
			(at -0.0508 -1.6764 0)
			(unlocked yes)
			(layer "F.Fab")
			(hide yes)
			(effects
				(font
					(size 1.016 1.016)
					(thickness 0.1524)
				)
			)
		)
		(property "Device Type" "TPAD32"
			(at -0.0508 -3.2004 0)
			(unlocked yes)
			(layer "F.Fab")
			(hide yes)
			(effects
				(font
					(size 1.016 1.016)
					(thickness 0.1524)
				)
			)
		)
		(duplicate_pad_numbers_are_jumpers no)
		(fp_poly
			(pts
				(arc
					(start 0.4064 0)
					(mid -0.4064 0)
					(end 0.4064 0)
				)
			)
			(stroke
				(width 0)
				(type default)
			)
			(fill no)
			(layer "F.CrtYd")
		)
		(fp_poly
			(pts
				(arc
					(start 0.7112 0)
					(mid -0.7112 0)
					(end 0.7112 0)
				)
			)
			(stroke
				(width 0)
				(type default)
			)
			(fill no)
			(layer "F.Fab")
		)
		(pad "1" smd circle
			(at 0 0)
			(size 0.8128 0.8128)
			(layers "F.Cu" "F.Mask" "F.Paste")
			(net "ACT_HDD_26")
		)
	)
	(footprint ""
		(layer "F.Cu")
		(at 85.199728 -159.874966 90)
		(property "Reference" "R463"
			(at 0 0 90)
			(layer "F.SilkS")
			(hide yes)
			(effects
				(font
					(size 1.27 1.27)
				)
			)
		)
		(property "Value" "0R2J-2-GP"
			(at 0.064008 -3.993896 90)
			(unlocked yes)
			(layer "F.Fab")
			(hide yes)
			(effects
				(font
					(size 1.016 1.016)
					(thickness 0.1524)
				)
			)
		)
		(property "Device Type" "R402H16"
			(at 0.064008 -5.517896 90)
			(unlocked yes)
			(layer "F.Fab")
			(hide yes)
			(effects
				(font
					(size 1.016 1.016)
					(thickness 0.1524)
				)
			)
		)
		(duplicate_pad_numbers_are_jumpers no)
		(fp_line
			(start 0.508 -0.9398)
			(end -0.508 -0.9398)
			(stroke
				(width 0.1524)
				(type default)
			)
			(layer "F.SilkS")
		)
		(fp_line
			(start -0.508 -0.9398)
			(end -0.508 0.9398)
			(stroke
				(width 0.1524)
				(type default)
			)
			(layer "F.SilkS")
		)
		(fp_rect
			(start -0.508 0.9398)
			(end 0.508 -0.9398)
			(stroke
				(width 0)
				(type default)
			)
			(fill no)
			(layer "F.CrtYd")
		)
		(fp_rect
			(start -0.508 0.9398)
			(end 0.508 -0.9398)
			(stroke
				(width 0)
				(type default)
			)
			(fill no)
			(layer "F.Fab")
		)
		(pad "1" smd custom
			(at 0 -0.4445 90)
			(size 0.1397 0.1397)
			(layers "F.Cu" "F.Mask" "F.Paste")
			(net "DRIVE_A_14_PWR")
			(options
				(clearance outline)
				(anchor circle)
			)
			(primitives
				(gr_poly
					(pts
						(arc
							(start -0.1778 -0.2794)
							(mid -0.249642 -0.249642)
							(end -0.2794 -0.1778)
						)
						(arc
							(start -0.2794 0.1778)
							(mid -0.249642 0.249642)
							(end -0.1778 0.2794)
						)
						(arc
							(start 0.1778 0.2794)
							(mid 0.249642 0.249642)
							(end 0.2794 0.1778)
						)
						(arc
							(start 0.2794 -0.1778)
							(mid 0.249642 -0.249642)
							(end 0.1778 -0.2794)
						)
					)
					(width 0)
					(fill yes)
				)
			)
		)
		(pad "2" smd custom
			(at 0 0.4445 90)
			(size 0.1397 0.1397)
			(layers "F.Cu" "F.Mask" "F.Paste")
			(net "SW_PWR_R_HDD14")
			(options
				(clearance outline)
				(anchor circle)
			)
			(primitives
				(gr_poly
					(pts
						(arc
							(start -0.1778 -0.2794)
							(mid -0.249642 -0.249642)
							(end -0.2794 -0.1778)
						)
						(arc
							(start -0.2794 0.1778)
							(mid -0.249642 0.249642)
							(end -0.1778 0.2794)
						)
						(arc
							(start 0.1778 0.2794)
							(mid 0.249642 0.249642)
							(end 0.2794 0.1778)
						)
						(arc
							(start 0.2794 -0.1778)
							(mid 0.249642 -0.249642)
							(end 0.1778 -0.2794)
						)
					)
					(width 0)
					(fill yes)
				)
			)
		)
	)
)
